# T6G (Grand Teton) — schematic netlist excerpt (pin names and nets, part order shuffled) for the footprints in the layout excerpt that follows; sources: Cadence DE-HDL packaged netlist, KiCad conversion of 04192023_DAF0TMB3IC0_F0TG_MB_C_brd_V02_OCP.brd

C452  Q_CAP  1UF 4V 20% X6S  pkg 0201  page 356 : A = P0V9_CPU1_RT3_2A ; B = GND
R253  Q_RES  0 5% CHIP  pkg 0402LF  page 81 : A = CPU0_NV_SAVE_N ; B = FM_CPU0_NV_SAVE_N
C2154  Q_CAP  22UF 4V 20% X6S  pkg C0402  page 68 : A = PVDDCR_SOC_P0 ; B = GND

(kicad_pcb
	(version 20260206)
	(generator "pcbnew")
	(generator_version "10.0")
	(general
		(thickness 1.6)
		(legacy_teardrops no)
	)
	(paper "A4")
	(title_block
		(title "04192023_DAF0TMB3IC0_F0TG_MB_C_brd_V02_OCP.brd")
		(comment 1 "Grand Teton / footprints 7841-7843 of 8354")
	)
	(layers
		(0 "F.Cu" signal "TOP")
		(4 "In1.Cu" signal "GND")
		(6 "In2.Cu" signal "IN1")
		(8 "In3.Cu" signal "GND1")
		(10 "In4.Cu" signal "IN2")
		(12 "In5.Cu" signal "GND2")
		(14 "In6.Cu" signal "IN3")
		(16 "In7.Cu" signal "GND3")
		(18 "In8.Cu" signal "VCC")
		(20 "In9.Cu" signal "VCC1")
		(22 "In10.Cu" signal "GND4")
		(24 "In11.Cu" signal "IN4")
		(26 "In12.Cu" signal "GND5")
		(28 "In13.Cu" signal "IN5")
		(30 "In14.Cu" signal "GND6")
		(32 "In15.Cu" signal "IN6")
		(34 "In16.Cu" signal "GND7")
		(2 "B.Cu" signal "BOTTOM")
		(9 "F.Adhes" user "F.Adhesive")
		(11 "B.Adhes" user "B.Adhesive")
		(13 "F.Paste" user "Package Geometry/Pastemask Top")
		(15 "B.Paste" user "Package Geometry/Pastemask Bottom")
		(5 "F.SilkS" user "Ref Des/Silkscreen Top")
		(7 "B.SilkS" user "Ref Des/Silkscreen Bottom")
		(1 "F.Mask" user "Board Geometry/Soldermask Top")
		(3 "B.Mask" user "Board Geometry/Soldermask Bottom")
		(17 "Dwgs.User" user "User.Drawings")
		(19 "Cmts.User" user "User.Comments")
		(21 "Eco1.User" user "User.Eco1")
		(23 "Eco2.User" user "User.Eco2")
		(25 "Edge.Cuts" user "Board Geometry/Outline")
		(27 "Margin" user)
		(31 "F.CrtYd" user "Package Geometry/Place Bound Top")
		(29 "B.CrtYd" user "Package Geometry/Place Bound Bottom")
		(35 "F.Fab" user "Ref Des/Assembly Top")
		(33 "B.Fab" user "Ref Des/Assembly Bottom")
	)
	(footprint ""
		(layer "B.Cu")
		(at 371.551454 -255.84531)
		(property "Reference" "C2154"
			(at 0 0 0)
			(layer "B.SilkS")
			(hide yes)
			(effects
				(font
					(size 1.27 1.27)
				)
				(justify mirror)
			)
		)
		(property "Value" ""
			(at 0 0 0)
			(layer "B.Fab")
			(effects
				(font
					(size 1.27 1.27)
				)
				(justify mirror)
			)
		)
		(duplicate_pad_numbers_are_jumpers no)
		(fp_line
			(start -0.7874 -0.4064)
			(end -0.7874 0.4064)
			(stroke
				(width 0.1524)
				(type default)
			)
			(layer "B.SilkS")
		)
		(fp_line
			(start -0.7874 0.4064)
			(end 0.7874 0.4064)
			(stroke
				(width 0.1524)
				(type default)
			)
			(layer "B.SilkS")
		)
		(fp_line
			(start 0.7874 -0.4064)
			(end -0.7874 -0.4064)
			(stroke
				(width 0.1524)
				(type default)
			)
			(layer "B.SilkS")
		)
		(fp_line
			(start 0.7874 0.4064)
			(end 0.7874 -0.4064)
			(stroke
				(width 0.1524)
				(type default)
			)
			(layer "B.SilkS")
		)
		(fp_line
			(start -0.67945 -0.3048)
			(end -0.67945 0.3048)
			(stroke
				(width 0.1)
				(type default)
			)
			(layer "B.Fab")
		)
		(fp_line
			(start -0.67945 0.3048)
			(end -0.120396 0.3048)
			(stroke
				(width 0.1)
				(type default)
			)
			(layer "B.Fab")
		)
		(fp_line
			(start -0.12065 -0.3048)
			(end -0.67945 -0.3048)
			(stroke
				(width 0.1)
				(type default)
			)
			(layer "B.Fab")
		)
		(fp_line
			(start -0.12065 -0.2794)
			(end -0.12065 -0.3048)
			(stroke
				(width 0.1)
				(type default)
			)
			(layer "B.Fab")
		)
		(fp_line
			(start -0.120396 0.2794)
			(end 0.12065 0.2794)
			(stroke
				(width 0.1)
				(type default)
			)
			(layer "B.Fab")
		)
		(fp_line
			(start -0.120396 0.3048)
			(end -0.120396 0.2794)
			(stroke
				(width 0.1)
				(type default)
			)
			(layer "B.Fab")
		)
		(fp_line
			(start 0.12065 -0.305054)
			(end 0.12065 -0.2794)
			(stroke
				(width 0.1)
				(type default)
			)
			(layer "B.Fab")
		)
		(fp_line
			(start 0.12065 -0.2794)
			(end -0.12065 -0.2794)
			(stroke
				(width 0.1)
				(type default)
			)
			(layer "B.Fab")
		)
		(fp_line
			(start 0.12065 0.2794)
			(end 0.12065 0.3048)
			(stroke
				(width 0.1)
				(type default)
			)
			(layer "B.Fab")
		)
		(fp_line
			(start 0.12065 0.3048)
			(end 0.67945 0.3048)
			(stroke
				(width 0.1)
				(type default)
			)
			(layer "B.Fab")
		)
		(fp_line
			(start 0.67945 -0.305054)
			(end 0.12065 -0.305054)
			(stroke
				(width 0.1)
				(type default)
			)
			(layer "B.Fab")
		)
		(fp_line
			(start 0.67945 0.3048)
			(end 0.67945 -0.305054)
			(stroke
				(width 0.1)
				(type default)
			)
			(layer "B.Fab")
		)
		(pad "1" smd circle
			(at 0.40005 0 180)
			(size 0 0)
			(layers "B.Cu" "B.Mask" "B.Paste")
			(net "PVDDCR_SOC_P0")
		)
		(pad "2" smd circle
			(at -0.40005 0 180)
			(size 0 0)
			(layers "B.Cu" "B.Mask" "B.Paste")
			(net "GND")
		)
	)
	(footprint ""
		(layer "B.Cu")
		(at 116.878608 -386.766562 90)
		(property "Reference" "C452"
			(at 0 0 90)
			(layer "B.SilkS")
			(hide yes)
			(effects
				(font
					(size 1.27 1.27)
				)
				(justify mirror)
			)
		)
		(property "Value" ""
			(at 0 0 90)
			(layer "B.Fab")
			(effects
				(font
					(size 1.27 1.27)
				)
				(justify mirror)
			)
		)
		(duplicate_pad_numbers_are_jumpers no)
		(fp_line
			(start 0.299974 -0.150114)
			(end -0.299974 -0.150114)
			(stroke
				(width 0.1)
				(type default)
			)
			(layer "B.Fab")
		)
		(fp_line
			(start -0.299974 -0.150114)
			(end -0.299974 0.150114)
			(stroke
				(width 0.1)
				(type default)
			)
			(layer "B.Fab")
		)
		(fp_line
			(start 0.299974 0.150114)
			(end 0.299974 -0.150114)
			(stroke
				(width 0.1)
				(type default)
			)
			(layer "B.Fab")
		)
		(fp_line
			(start -0.299974 0.150114)
			(end 0.299974 0.150114)
			(stroke
				(width 0.1)
				(type default)
			)
			(layer "B.Fab")
		)
		(pad "1" smd rect
			(at 0.2667 0 270)
			(size 0.3048 0.381)
			(layers "B.Cu" "B.Mask" "B.Paste")
			(net "P0V9_CPU1_RT3_2A")
		)
		(pad "2" smd rect
			(at -0.2667 0 270)
			(size 0.3048 0.381)
			(layers "B.Cu" "B.Mask" "B.Paste")
			(net "GND")
		)
	)
	(footprint ""
		(layer "B.Cu")
		(at 181.013608 -126.833376 90)
		(property "Reference" "R253"
			(at 0 0 90)
			(layer "B.SilkS")
			(hide yes)
			(effects
				(font
					(size 1.27 1.27)
				)
				(justify mirror)
			)
		)
		(property "Value" ""
			(at 0 0 90)
			(layer "B.Fab")
			(effects
				(font
					(size 1.27 1.27)
				)
				(justify mirror)
			)
		)
		(duplicate_pad_numbers_are_jumpers no)
		(fp_line
			(start 0.7874 -0.4064)
			(end -0.7874 -0.4064)
			(stroke
				(width 0.1524)
				(type default)
			)
			(layer "B.SilkS")
		)
		(fp_line
			(start -0.7874 -0.4064)
			(end -0.7874 0.4064)
			(stroke
				(width 0.1524)
				(type default)
			)
			(layer "B.SilkS")
		)
		(fp_line
			(start 0.7874 0.4064)
			(end 0.7874 -0.4064)
			(stroke
				(width 0.1524)
				(type default)
			)
			(layer "B.SilkS")
		)
		(fp_line
			(start -0.7874 0.4064)
			(end 0.7874 0.4064)
			(stroke
				(width 0.1524)
				(type default)
			)
			(layer "B.SilkS")
		)
		(fp_line
			(start 0.67945 -0.305054)
			(end 0.12065 -0.305054)
			(stroke
				(width 0.1)
				(type default)
			)
			(layer "B.Fab")
		)
		(fp_line
			(start 0.12065 -0.305054)
			(end 0.12065 -0.2794)
			(stroke
				(width 0.1)
				(type default)
			)
			(layer "B.Fab")
		)
		(fp_line
			(start -0.12065 -0.3048)
			(end -0.67945 -0.3048)
			(stroke
				(width 0.1)
				(type default)
			)
			(layer "B.Fab")
		)
		(fp_line
			(start -0.67945 -0.3048)
			(end -0.67945 0.3048)
			(stroke
				(width 0.1)
				(type default)
			)
			(layer "B.Fab")
		)
		(fp_line
			(start 0.12065 -0.2794)
			(end -0.12065 -0.2794)
			(stroke
				(width 0.1)
				(type default)
			)
			(layer "B.Fab")
		)
		(fp_line
			(start -0.12065 -0.2794)
			(end -0.12065 -0.3048)
			(stroke
				(width 0.1)
				(type default)
			)
			(layer "B.Fab")
		)
		(fp_line
			(start 0.12065 0.2794)
			(end 0.12065 0.3048)
			(stroke
				(width 0.1)
				(type default)
			)
			(layer "B.Fab")
		)
		(fp_line
			(start -0.120396 0.2794)
			(end 0.12065 0.2794)
			(stroke
				(width 0.1)
				(type default)
			)
			(layer "B.Fab")
		)
		(fp_line
			(start 0.67945 0.3048)
			(end 0.67945 -0.305054)
			(stroke
				(width 0.1)
				(type default)
			)
			(layer "B.Fab")
		)
		(fp_line
			(start 0.12065 0.3048)
			(end 0.67945 0.3048)
			(stroke
				(width 0.1)
				(type default)
			)
			(layer "B.Fab")
		)
		(fp_line
			(start -0.120396 0.3048)
			(end -0.120396 0.2794)
			(stroke
				(width 0.1)
				(type default)
			)
			(layer "B.Fab")
		)
		(fp_line
			(start -0.67945 0.3048)
			(end -0.120396 0.3048)
			(stroke
				(width 0.1)
				(type default)
			)
			(layer "B.Fab")
		)
		(pad "1" smd circle
			(at 0.40005 0 270)
			(size 0 0)
			(layers "B.Cu" "B.Mask" "B.Paste")
			(net "CPU0_NV_SAVE_N")
		)
		(pad "2" smd circle
			(at -0.40005 0 270)
			(size 0 0)
			(layers "B.Cu" "B.Mask" "B.Paste")
			(net "FM_CPU0_NV_SAVE_N")
		)
	)
)
